(kicad_pcb
	(version 20260206)
	(generator "pcbnew")
	(generator_version "10.0")
	(general
		(thickness 1.6)
		(legacy_teardrops no)
	)
	(paper "A4")
	(title_block
		(title "03242023_DA0F0TMBIJ0_F0T_Motherboard_J_brd_V01_OCP.brd")
		(comment 1 "Grand Teton / footprints 1142-1148 of 6105")
	)
	(layers
		(0 "F.Cu" signal "TOP")
		(4 "In1.Cu" signal "GND")
		(6 "In2.Cu" signal "IN1")
		(8 "In3.Cu" signal "GND1")
		(10 "In4.Cu" signal "IN2")
		(12 "In5.Cu" signal "GND2")
		(14 "In6.Cu" signal "IN3")
		(16 "In7.Cu" signal "GND3")
		(18 "In8.Cu" signal "VCC")
		(20 "In9.Cu" signal "VCC1")
		(22 "In10.Cu" signal "GND4")
		(24 "In11.Cu" signal "IN4")
		(26 "In12.Cu" signal "GND5")
		(28 "In13.Cu" signal "IN5")
		(30 "In14.Cu" signal "GND6")
		(32 "In15.Cu" signal "IN6")
		(34 "In16.Cu" signal "GND7")
		(2 "B.Cu" signal "BOTTOM")
		(9 "F.Adhes" user "F.Adhesive")
		(11 "B.Adhes" user "B.Adhesive")
		(13 "F.Paste" user "Package Geometry/Pastemask Top")
		(15 "B.Paste" user "Package Geometry/Pastemask Bottom")
		(5 "F.SilkS" user "Ref Des/Silkscreen Top")
		(7 "B.SilkS" user "Ref Des/Silkscreen Bottom")
		(1 "F.Mask" user "Board Geometry/Soldermask Top")
		(3 "B.Mask" user "Board Geometry/Soldermask Bottom")
		(17 "Dwgs.User" user "User.Drawings")
		(19 "Cmts.User" user "User.Comments")
		(21 "Eco1.User" user "User.Eco1")
		(23 "Eco2.User" user "User.Eco2")
		(25 "Edge.Cuts" user "Board Geometry/Outline")
		(27 "Margin" user)
		(31 "F.CrtYd" user "Package Geometry/Place Bound Top")
		(29 "B.CrtYd" user "Package Geometry/Place Bound Bottom")
		(35 "F.Fab" user "Ref Des/Assembly Top")
		(33 "B.Fab" user "Ref Des/Assembly Bottom")
	)
	(footprint ""
		(layer "F.Cu")
		(at 253.08941 -44.849542 90)
		(property "Reference" "PR3968"
			(at 0 0 90)
			(layer "F.SilkS")
			(hide yes)
			(effects
				(font
					(size 1.27 1.27)
				)
			)
		)
		(property "Value" ""
			(at 0 0 90)
			(layer "F.Fab")
			(effects
				(font
					(size 1.27 1.27)
				)
			)
		)
		(duplicate_pad_numbers_are_jumpers no)
		(fp_line
			(start 0.7874 -0.4064)
			(end 0.7874 0.4064)
			(stroke
				(width 0.1524)
				(type default)
			)
			(layer "F.SilkS")
		)
		(fp_line
			(start -0.7874 -0.4064)
			(end 0.7874 -0.4064)
			(stroke
				(width 0.1524)
				(type default)
			)
			(layer "F.SilkS")
		)
		(fp_line
			(start 0.7874 0.4064)
			(end -0.7874 0.4064)
			(stroke
				(width 0.1524)
				(type default)
			)
			(layer "F.SilkS")
		)
		(fp_line
			(start -0.7874 0.4064)
			(end -0.7874 -0.4064)
			(stroke
				(width 0.1524)
				(type default)
			)
			(layer "F.SilkS")
		)
		(fp_line
			(start -0.12065 -0.305054)
			(end -0.12065 -0.2794)
			(stroke
				(width 0.1)
				(type default)
			)
			(layer "F.Fab")
		)
		(fp_line
			(start -0.67945 -0.305054)
			(end -0.12065 -0.305054)
			(stroke
				(width 0.1)
				(type default)
			)
			(layer "F.Fab")
		)
		(fp_line
			(start 0.67945 -0.3048)
			(end 0.67945 0.3048)
			(stroke
				(width 0.1)
				(type default)
			)
			(layer "F.Fab")
		)
		(fp_line
			(start 0.12065 -0.3048)
			(end 0.67945 -0.3048)
			(stroke
				(width 0.1)
				(type default)
			)
			(layer "F.Fab")
		)
		(fp_line
			(start 0.12065 -0.2794)
			(end 0.12065 -0.3048)
			(stroke
				(width 0.1)
				(type default)
			)
			(layer "F.Fab")
		)
		(fp_line
			(start -0.12065 -0.2794)
			(end 0.12065 -0.2794)
			(stroke
				(width 0.1)
				(type default)
			)
			(layer "F.Fab")
		)
		(fp_line
			(start 0.120396 0.2794)
			(end -0.12065 0.2794)
			(stroke
				(width 0.1)
				(type default)
			)
			(layer "F.Fab")
		)
		(fp_line
			(start -0.12065 0.2794)
			(end -0.12065 0.3048)
			(stroke
				(width 0.1)
				(type default)
			)
			(layer "F.Fab")
		)
		(fp_line
			(start 0.67945 0.3048)
			(end 0.120396 0.3048)
			(stroke
				(width 0.1)
				(type default)
			)
			(layer "F.Fab")
		)
		(fp_line
			(start 0.120396 0.3048)
			(end 0.120396 0.2794)
			(stroke
				(width 0.1)
				(type default)
			)
			(layer "F.Fab")
		)
		(fp_line
			(start -0.12065 0.3048)
			(end -0.67945 0.3048)
			(stroke
				(width 0.1)
				(type default)
			)
			(layer "F.Fab")
		)
		(fp_line
			(start -0.67945 0.3048)
			(end -0.67945 -0.305054)
			(stroke
				(width 0.1)
				(type default)
			)
			(layer "F.Fab")
		)
		(pad "1" smd circle
			(at -0.40005 0 90)
			(size 0 0)
			(layers "F.Cu" "F.Mask" "F.Paste")
			(net "P12V_E1S_CB_0")
		)
		(pad "2" smd circle
			(at 0.40005 0 90)
			(size 0 0)
			(layers "F.Cu" "F.Mask" "F.Paste")
			(net "GND")
		)
	)
	(footprint ""
		(layer "F.Cu")
		(at 287.979866 -419.999922)
		(property "Reference" "H129"
			(at -3.46456 -4.95681 0)
			(unlocked yes)
			(layer "F.SilkS")
			(effects
				(font
					(size 0.7874 0.5842)
					(thickness 0.1524)
				)
				(justify left)
			)
		)
		(property "Value" ""
			(at 0 0 0)
			(layer "F.Fab")
			(effects
				(font
					(size 1.27 1.27)
				)
			)
		)
		(duplicate_pad_numbers_are_jumpers no)
		(pad "1" thru_hole circle
			(at 0 0)
			(size 8.001 8.001)
			(drill 4.2164)
			(layers "*.Cu" "*.Mask")
			(remove_unused_layers no)
			(net "GND")
			(clearance -1.6383)
		)
	)
	(footprint ""
		(layer "F.Cu")
		(at 463.562954 -92.387674)
		(property "Reference" "R3233"
			(at 0 0 0)
			(layer "F.SilkS")
			(hide yes)
			(effects
				(font
					(size 1.27 1.27)
				)
			)
		)
		(property "Value" ""
			(at 0 0 0)
			(layer "F.Fab")
			(effects
				(font
					(size 1.27 1.27)
				)
			)
		)
		(duplicate_pad_numbers_are_jumpers no)
		(fp_line
			(start -0.7874 -0.4064)
			(end 0.7874 -0.4064)
			(stroke
				(width 0.1524)
				(type default)
			)
			(layer "F.SilkS")
		)
		(fp_line
			(start -0.7874 0.4064)
			(end -0.7874 -0.4064)
			(stroke
				(width 0.1524)
				(type default)
			)
			(layer "F.SilkS")
		)
		(fp_line
			(start 0.7874 -0.4064)
			(end 0.7874 0.4064)
			(stroke
				(width 0.1524)
				(type default)
			)
			(layer "F.SilkS")
		)
		(fp_line
			(start 0.7874 0.4064)
			(end -0.7874 0.4064)
			(stroke
				(width 0.1524)
				(type default)
			)
			(layer "F.SilkS")
		)
		(fp_line
			(start -0.67945 -0.305054)
			(end -0.12065 -0.305054)
			(stroke
				(width 0.1)
				(type default)
			)
			(layer "F.Fab")
		)
		(fp_line
			(start -0.67945 0.3048)
			(end -0.67945 -0.305054)
			(stroke
				(width 0.1)
				(type default)
			)
			(layer "F.Fab")
		)
		(fp_line
			(start -0.12065 -0.305054)
			(end -0.12065 -0.2794)
			(stroke
				(width 0.1)
				(type default)
			)
			(layer "F.Fab")
		)
		(fp_line
			(start -0.12065 -0.2794)
			(end 0.12065 -0.2794)
			(stroke
				(width 0.1)
				(type default)
			)
			(layer "F.Fab")
		)
		(fp_line
			(start -0.12065 0.2794)
			(end -0.12065 0.3048)
			(stroke
				(width 0.1)
				(type default)
			)
			(layer "F.Fab")
		)
		(fp_line
			(start -0.12065 0.3048)
			(end -0.67945 0.3048)
			(stroke
				(width 0.1)
				(type default)
			)
			(layer "F.Fab")
		)
		(fp_line
			(start 0.120396 0.2794)
			(end -0.12065 0.2794)
			(stroke
				(width 0.1)
				(type default)
			)
			(layer "F.Fab")
		)
		(fp_line
			(start 0.120396 0.3048)
			(end 0.120396 0.2794)
			(stroke
				(width 0.1)
				(type default)
			)
			(layer "F.Fab")
		)
		(fp_line
			(start 0.12065 -0.3048)
			(end 0.67945 -0.3048)
			(stroke
				(width 0.1)
				(type default)
			)
			(layer "F.Fab")
		)
		(fp_line
			(start 0.12065 -0.2794)
			(end 0.12065 -0.3048)
			(stroke
				(width 0.1)
				(type default)
			)
			(layer "F.Fab")
		)
		(fp_line
			(start 0.67945 -0.3048)
			(end 0.67945 0.3048)
			(stroke
				(width 0.1)
				(type default)
			)
			(layer "F.Fab")
		)
		(fp_line
			(start 0.67945 0.3048)
			(end 0.120396 0.3048)
			(stroke
				(width 0.1)
				(type default)
			)
			(layer "F.Fab")
		)
		(pad "1" smd circle
			(at -0.40005 0)
			(size 0 0)
			(layers "F.Cu" "F.Mask" "F.Paste")
			(net "RST_HP_OCP_SFF_R_N")
		)
		(pad "2" smd circle
			(at 0.40005 0)
			(size 0 0)
			(layers "F.Cu" "F.Mask" "F.Paste")
			(net "RST_SMB_OCP_SFF_N")
		)
	)
	(footprint ""
		(layer "F.Cu")
		(at 107.975146 -99.609402)
		(property "Reference" "Q86"
			(at 2.133854 -1.933956 0)
			(unlocked yes)
			(layer "F.SilkS")
			(effects
				(font
					(size 0.7874 0.5842)
					(thickness 0.1524)
				)
				(justify left)
			)
		)
		(property "Value" ""
			(at 0 0 0)
			(layer "F.Fab")
			(effects
				(font
					(size 1.27 1.27)
				)
			)
		)
		(duplicate_pad_numbers_are_jumpers no)
		(fp_line
			(start -1.332738 -1.100074)
			(end -0.4826 -1.100074)
			(stroke
				(width 0.1524)
				(type default)
			)
			(layer "F.SilkS")
		)
		(fp_line
			(start -1.332738 1.100074)
			(end -1.332738 -1.100074)
			(stroke
				(width 0.1524)
				(type default)
			)
			(layer "F.SilkS")
		)
		(fp_line
			(start -0.4826 -1.100074)
			(end 0 -0.541274)
			(stroke
				(width 0.1524)
				(type default)
			)
			(layer "F.SilkS")
		)
		(fp_line
			(start 0 -0.541274)
			(end 0.4826 -1.100074)
			(stroke
				(width 0.1524)
				(type default)
			)
			(layer "F.SilkS")
		)
		(fp_line
			(start 0.4826 -1.100074)
			(end 1.332738 -1.100074)
			(stroke
				(width 0.1524)
				(type default)
			)
			(layer "F.SilkS")
		)
		(fp_line
			(start 1.332738 -1.100074)
			(end 1.332738 1.100074)
			(stroke
				(width 0.1524)
				(type default)
			)
			(layer "F.SilkS")
		)
		(fp_line
			(start 1.332738 1.100074)
			(end -1.332738 1.100074)
			(stroke
				(width 0.1524)
				(type default)
			)
			(layer "F.SilkS")
		)
		(fp_poly
			(pts
				(xy -0.634238 -1.97358) (xy -0.985266 -1.271524) (xy -1.336294 -1.97358)
			)
			(stroke
				(width 0)
				(type default)
			)
			(fill yes)
			(layer "F.SilkS")
		)
		(fp_line
			(start -0.674878 -1.100074)
			(end 0.674878 -1.100074)
			(stroke
				(width 0.1)
				(type default)
			)
			(layer "F.Fab")
		)
		(fp_line
			(start -0.674878 1.100074)
			(end -0.674878 -1.100074)
			(stroke
				(width 0.1)
				(type default)
			)
			(layer "F.Fab")
		)
		(fp_line
			(start 0.674878 -1.100074)
			(end 0.674878 1.100074)
			(stroke
				(width 0.1)
				(type default)
			)
			(layer "F.Fab")
		)
		(fp_line
			(start 0.674878 1.100074)
			(end -0.674878 1.100074)
			(stroke
				(width 0.1)
				(type default)
			)
			(layer "F.Fab")
		)
		(fp_poly
			(pts
				(xy -2.2352 -0.298958) (xy -2.2352 -1.001014) (xy -1.533144 -0.649986)
			)
			(stroke
				(width 0)
				(type default)
			)
			(fill yes)
			(layer "F.Fab")
		)
		(pad "1" smd rect
			(at -0.94996 -0.649986 90)
			(size 0.4318 0.508)
			(layers "F.Cu" "F.Mask" "F.Paste")
			(net "GND")
		)
		(pad "2" smd rect
			(at -0.94996 0 90)
			(size 0.4318 0.508)
			(layers "F.Cu" "F.Mask" "F.Paste")
			(net "PWRGD_PVCCINFAON_CPU1")
		)
		(pad "3" smd rect
			(at -0.94996 0.649986 90)
			(size 0.4318 0.508)
			(layers "F.Cu" "F.Mask" "F.Paste")
			(net "LED_PWRGD_PVNN_MAIN_CPU1_D")
		)
		(pad "4" smd rect
			(at 0.94996 0.649986 90)
			(size 0.4318 0.508)
			(layers "F.Cu" "F.Mask" "F.Paste")
			(net "GND")
		)
		(pad "5" smd rect
			(at 0.94996 0 90)
			(size 0.4318 0.508)
			(layers "F.Cu" "F.Mask" "F.Paste")
			(net "PWRGD_PVNN_MAIN_CPU1")
		)
		(pad "6" smd rect
			(at 0.94996 -0.649986 90)
			(size 0.4318 0.508)
			(layers "F.Cu" "F.Mask" "F.Paste")
			(net "LED_PWRGD_PVCCINFAON_CPU1_D")
		)
	)
	(footprint ""
		(layer "F.Cu")
		(at 101.219 -40.231568)
		(property "Reference" "U207"
			(at -1.778 -1.819148 0)
			(unlocked yes)
			(layer "F.SilkS")
			(effects
				(font
					(size 0.7874 0.5842)
					(thickness 0.1524)
				)
				(justify left)
			)
		)
		(property "Value" ""
			(at 0 0 0)
			(layer "F.Fab")
			(effects
				(font
					(size 1.27 1.27)
				)
			)
		)
		(duplicate_pad_numbers_are_jumpers no)
		(fp_line
			(start -1.695958 -1.124966)
			(end 1.695958 -1.124966)
			(stroke
				(width 0.1524)
				(type default)
			)
			(layer "F.SilkS")
		)
		(fp_line
			(start -1.695958 1.124966)
			(end -1.695958 -1.124966)
			(stroke
				(width 0.1524)
				(type default)
			)
			(layer "F.SilkS")
		)
		(fp_line
			(start 1.695958 -1.124966)
			(end 1.695958 1.124966)
			(stroke
				(width 0.1524)
				(type default)
			)
			(layer "F.SilkS")
		)
		(fp_line
			(start 1.695958 1.124966)
			(end -1.695958 1.124966)
			(stroke
				(width 0.1524)
				(type default)
			)
			(layer "F.SilkS")
		)
		(fp_poly
			(pts
				(xy -1.96342 -0.680466) (xy -2.58318 -0.370586) (xy -2.58318 -0.990346)
			)
			(stroke
				(width 0)
				(type default)
			)
			(fill yes)
			(layer "F.SilkS")
		)
		(fp_line
			(start -0.674878 -1.124966)
			(end 0.674878 -1.124966)
			(stroke
				(width 0.1)
				(type default)
			)
			(layer "F.Fab")
		)
		(fp_line
			(start -0.674878 1.124966)
			(end -0.674878 -1.124966)
			(stroke
				(width 0.1)
				(type default)
			)
			(layer "F.Fab")
		)
		(fp_line
			(start 0.674878 -1.124966)
			(end 0.674878 1.124966)
			(stroke
				(width 0.1)
				(type default)
			)
			(layer "F.Fab")
		)
		(fp_line
			(start 0.674878 1.124966)
			(end -0.674878 1.124966)
			(stroke
				(width 0.1)
				(type default)
			)
			(layer "F.Fab")
		)
		(fp_poly
			(pts
				(xy -2.4892 -0.959866) (xy -1.86944 -0.649986) (xy -2.4892 -0.340106)
			)
			(stroke
				(width 0)
				(type default)
			)
			(fill yes)
			(layer "F.Fab")
		)
		(pad "1" smd rect
			(at -0.94488 -0.649986 90)
			(size 0.3556 1.2446)
			(layers "F.Cu" "F.Mask" "F.Paste")
			(net "Net_1690")
		)
		(pad "2" smd rect
			(at -0.94488 0 90)
			(size 0.3556 1.2446)
			(layers "F.Cu" "F.Mask" "F.Paste")
			(net "RST_HP_OCP_V3_2_N")
		)
		(pad "3" smd rect
			(at -0.94488 0.649986 90)
			(size 0.3556 1.2446)
			(layers "F.Cu" "F.Mask" "F.Paste")
			(net "GND")
		)
		(pad "4" smd rect
			(at 0.94488 0.649986 90)
			(size 0.3556 1.2446)
			(layers "F.Cu" "F.Mask" "F.Paste")
			(net "RST_OCP_V3_2_BUF_N")
		)
		(pad "5" smd rect
			(at 0.94488 -0.649986 90)
			(size 0.3556 1.2446)
			(layers "F.Cu" "F.Mask" "F.Paste")
			(net "P3V3_AUX")
		)
	)
	(footprint ""
		(layer "F.Cu")
		(at 22.64156 -169.604436 180)
		(property "Reference" "C2454"
			(at 0 0 180)
			(layer "F.SilkS")
			(hide yes)
			(effects
				(font
					(size 1.27 1.27)
				)
			)
		)
		(property "Value" ""
			(at 0 0 180)
			(layer "F.Fab")
			(effects
				(font
					(size 1.27 1.27)
				)
			)
		)
		(duplicate_pad_numbers_are_jumpers no)
		(fp_line
			(start 0.7874 0.4064)
			(end -0.7874 0.4064)
			(stroke
				(width 0.1524)
				(type default)
			)
			(layer "F.SilkS")
		)
		(fp_line
			(start 0.7874 -0.4064)
			(end 0.7874 0.4064)
			(stroke
				(width 0.1524)
				(type default)
			)
			(layer "F.SilkS")
		)
		(fp_line
			(start -0.7874 0.4064)
			(end -0.7874 -0.4064)
			(stroke
				(width 0.1524)
				(type default)
			)
			(layer "F.SilkS")
		)
		(fp_line
			(start -0.7874 -0.4064)
			(end 0.7874 -0.4064)
			(stroke
				(width 0.1524)
				(type default)
			)
			(layer "F.SilkS")
		)
		(fp_line
			(start 0.67945 0.3048)
			(end 0.120396 0.3048)
			(stroke
				(width 0.1)
				(type default)
			)
			(layer "F.Fab")
		)
		(fp_line
			(start 0.67945 -0.3048)
			(end 0.67945 0.3048)
			(stroke
				(width 0.1)
				(type default)
			)
			(layer "F.Fab")
		)
		(fp_line
			(start 0.12065 -0.2794)
			(end 0.12065 -0.3048)
			(stroke
				(width 0.1)
				(type default)
			)
			(layer "F.Fab")
		)
		(fp_line
			(start 0.12065 -0.3048)
			(end 0.67945 -0.3048)
			(stroke
				(width 0.1)
				(type default)
			)
			(layer "F.Fab")
		)
		(fp_line
			(start 0.120396 0.3048)
			(end 0.120396 0.2794)
			(stroke
				(width 0.1)
				(type default)
			)
			(layer "F.Fab")
		)
		(fp_line
			(start 0.120396 0.2794)
			(end -0.12065 0.2794)
			(stroke
				(width 0.1)
				(type default)
			)
			(layer "F.Fab")
		)
		(fp_line
			(start -0.12065 0.3048)
			(end -0.67945 0.3048)
			(stroke
				(width 0.1)
				(type default)
			)
			(layer "F.Fab")
		)
		(fp_line
			(start -0.12065 0.2794)
			(end -0.12065 0.3048)
			(stroke
				(width 0.1)
				(type default)
			)
			(layer "F.Fab")
		)
		(fp_line
			(start -0.12065 -0.2794)
			(end 0.12065 -0.2794)
			(stroke
				(width 0.1)
				(type default)
			)
			(layer "F.Fab")
		)
		(fp_line
			(start -0.12065 -0.305054)
			(end -0.12065 -0.2794)
			(stroke
				(width 0.1)
				(type default)
			)
			(layer "F.Fab")
		)
		(fp_line
			(start -0.67945 0.3048)
			(end -0.67945 -0.305054)
			(stroke
				(width 0.1)
				(type default)
			)
			(layer "F.Fab")
		)
		(fp_line
			(start -0.67945 -0.305054)
			(end -0.12065 -0.305054)
			(stroke
				(width 0.1)
				(type default)
			)
			(layer "F.Fab")
		)
		(pad "1" smd circle
			(at -0.40005 0 180)
			(size 0 0)
			(layers "F.Cu" "F.Mask" "F.Paste")
			(net "PWRGD_PVCCD_HV_CPU1_R")
		)
		(pad "2" smd circle
			(at 0.40005 0 180)
			(size 0 0)
			(layers "F.Cu" "F.Mask" "F.Paste")
			(net "GND")
		)
	)
	(footprint ""
		(layer "F.Cu")
		(at 218.08948 -127.803148)
		(property "Reference" "C1318"
			(at 0 0 0)
			(layer "F.SilkS")
			(hide yes)
			(effects
				(font
					(size 1.27 1.27)
				)
			)
		)
		(property "Value" ""
			(at 0 0 0)
			(layer "F.Fab")
			(effects
				(font
					(size 1.27 1.27)
				)
			)
		)
		(duplicate_pad_numbers_are_jumpers no)
		(fp_line
			(start -0.7874 -0.4064)
			(end 0.7874 -0.4064)
			(stroke
				(width 0.1524)
				(type default)
			)
			(layer "F.SilkS")
		)
		(fp_line
			(start -0.7874 0.4064)
			(end -0.7874 -0.4064)
			(stroke
				(width 0.1524)
				(type default)
			)
			(layer "F.SilkS")
		)
		(fp_line
			(start 0.7874 -0.4064)
			(end 0.7874 0.4064)
			(stroke
				(width 0.1524)
				(type default)
			)
			(layer "F.SilkS")
		)
		(fp_line
			(start 0.7874 0.4064)
			(end -0.7874 0.4064)
			(stroke
				(width 0.1524)
				(type default)
			)
			(layer "F.SilkS")
		)
		(fp_line
			(start -0.67945 -0.305054)
			(end -0.12065 -0.305054)
			(stroke
				(width 0.1)
				(type default)
			)
			(layer "F.Fab")
		)
		(fp_line
			(start -0.67945 0.3048)
			(end -0.67945 -0.305054)
			(stroke
				(width 0.1)
				(type default)
			)
			(layer "F.Fab")
		)
		(fp_line
			(start -0.12065 -0.305054)
			(end -0.12065 -0.2794)
			(stroke
				(width 0.1)
				(type default)
			)
			(layer "F.Fab")
		)
		(fp_line
			(start -0.12065 -0.2794)
			(end 0.12065 -0.2794)
			(stroke
				(width 0.1)
				(type default)
			)
			(layer "F.Fab")
		)
		(fp_line
			(start -0.12065 0.2794)
			(end -0.12065 0.3048)
			(stroke
				(width 0.1)
				(type default)
			)
			(layer "F.Fab")
		)
		(fp_line
			(start -0.12065 0.3048)
			(end -0.67945 0.3048)
			(stroke
				(width 0.1)
				(type default)
			)
			(layer "F.Fab")
		)
		(fp_line
			(start 0.120396 0.2794)
			(end -0.12065 0.2794)
			(stroke
				(width 0.1)
				(type default)
			)
			(layer "F.Fab")
		)
		(fp_line
			(start 0.120396 0.3048)
			(end 0.120396 0.2794)
			(stroke
				(width 0.1)
				(type default)
			)
			(layer "F.Fab")
		)
		(fp_line
			(start 0.12065 -0.3048)
			(end 0.67945 -0.3048)
			(stroke
				(width 0.1)
				(type default)
			)
			(layer "F.Fab")
		)
		(fp_line
			(start 0.12065 -0.2794)
			(end 0.12065 -0.3048)
			(stroke
				(width 0.1)
				(type default)
			)
			(layer "F.Fab")
		)
		(fp_line
			(start 0.67945 -0.3048)
			(end 0.67945 0.3048)
			(stroke
				(width 0.1)
				(type default)
			)
			(layer "F.Fab")
		)
		(fp_line
			(start 0.67945 0.3048)
			(end 0.120396 0.3048)
			(stroke
				(width 0.1)
				(type default)
			)
			(layer "F.Fab")
		)
		(pad "1" smd circle
			(at -0.40005 0)
			(size 0 0)
			(layers "F.Cu" "F.Mask" "F.Paste")
			(net "PWRGD_DSW_PWROK_R1")
		)
		(pad "2" smd circle
			(at 0.40005 0)
			(size 0 0)
			(layers "F.Cu" "F.Mask" "F.Paste")
			(net "GND")
		)
	)
)
